(kicad_pcb
	(version 20260206)
	(generator "pcbnew")
	(generator_version "10.0")
	(general
		(thickness 1.6)
		(legacy_teardrops no)
	)
	(paper "A4")
	(title_block
		(title "dpb — 14545-sa.0730WZS0815.brd")
		(comment 1 "Honey Badger (Wiwynn) / footprint 511 of 1066 (CN2), pads 1-93 of 166")
	)
	(layers
		(0 "F.Cu" signal "TOP")
		(4 "In1.Cu" signal "L2GND")
		(6 "In2.Cu" signal "L3")
		(8 "In3.Cu" signal "L4VCC")
		(10 "In4.Cu" signal "L5VCC")
		(12 "In5.Cu" signal "L6")
		(14 "In6.Cu" signal "L7GND")
		(2 "B.Cu" signal "BOTTOM")
		(9 "F.Adhes" user "F.Adhesive")
		(11 "B.Adhes" user "B.Adhesive")
		(13 "F.Paste" user "Package Geometry/Pastemask Top")
		(15 "B.Paste" user "Package Geometry/Pastemask Bottom")
		(5 "F.SilkS" user "Ref Des/Silkscreen Top")
		(7 "B.SilkS" user "Ref Des/Silkscreen Bottom")
		(1 "F.Mask" user "Board Geometry/Soldermask Top")
		(3 "B.Mask" user "Board Geometry/Soldermask Bottom")
		(17 "Dwgs.User" user "User.Drawings")
		(19 "Cmts.User" user "User.Comments")
		(21 "Eco1.User" user "User.Eco1")
		(23 "Eco2.User" user "User.Eco2")
		(25 "Edge.Cuts" user "Board Geometry/Outline")
		(27 "Margin" user)
		(31 "F.CrtYd" user "Package Geometry/Place Bound Top")
		(29 "B.CrtYd" user "Package Geometry/Place Bound Bottom")
		(35 "F.Fab" user "Ref Des/Assembly Top")
		(33 "B.Fab" user "Ref Des/Assembly Bottom")
	)
	(footprint ""
		(layer "F.Cu")
		(at 2.500122 -105.998518 -90)
		(property "Reference" "CN2"
			(at 0 0 270)
			(layer "F.SilkS")
			(hide yes)
			(effects
				(font
					(size 1.27 1.27)
				)
			)
		)
		(property "Value" "PCISLT164-70-GP"
			(at -77.8764 -6.4262 270)
			(unlocked yes)
			(layer "F.Fab")
			(hide yes)
			(effects
				(font
					(size 1.016 1.016)
					(thickness 0.1524)
				)
			)
		)
		(property "Device Type" "G630EAA12048EU"
			(at -77.8764 -7.9502 270)
			(unlocked yes)
			(layer "F.Fab")
			(hide yes)
			(effects
				(font
					(size 1.016 1.016)
					(thickness 0.1524)
				)
			)
		)
		(duplicate_pad_numbers_are_jumpers no)
		(pad "" np_thru_hole circle
			(at -76.300076 0 270)
			(size 0.254 0.254)
			(drill 2.3114)
			(layers "*.Cu" "*.Mask")
			(clearance 1.3843)
			(thermal_gap 1.3843)
		)
		(pad "" np_thru_hole circle
			(at 16.299942 0 270)
			(size 0.254 0.254)
			(drill 2.3114)
			(layers "*.Cu" "*.Mask")
			(clearance 1.3843)
			(thermal_gap 1.3843)
		)
		(pad "A1" smd rect
			(at 11.500104 -0.311404 270)
			(size 0.7112 3.6068)
			(drill
				(offset 0 -0.381)
			)
			(layers "F.Cu" "F.Mask" "F.Paste")
			(net "GND")
		)
		(pad "A2" smd rect
			(at 10.500106 -0.311404 270)
			(size 0.7112 3.6068)
			(drill
				(offset 0 -0.381)
			)
			(layers "F.Cu" "F.Mask" "F.Paste")
			(net "SAS2X28_B_HDD14_RX_+")
		)
		(pad "A3" smd rect
			(at 9.500108 -0.311404 270)
			(size 0.7112 3.6068)
			(drill
				(offset 0 -0.381)
			)
			(layers "F.Cu" "F.Mask" "F.Paste")
			(net "SAS2X28_B_HDD14_RX_-")
		)
		(pad "A4" smd rect
			(at 8.50011 -0.311404 270)
			(size 0.7112 3.6068)
			(drill
				(offset 0 -0.381)
			)
			(layers "F.Cu" "F.Mask" "F.Paste")
			(net "GND")
		)
		(pad "A5" smd rect
			(at 7.500112 -0.311404 270)
			(size 0.7112 3.6068)
			(drill
				(offset 0 -0.381)
			)
			(layers "F.Cu" "F.Mask" "F.Paste")
			(net "GND")
		)
		(pad "A6" smd rect
			(at 6.500114 -0.311404 270)
			(size 0.7112 3.6068)
			(drill
				(offset 0 -0.381)
			)
			(layers "F.Cu" "F.Mask" "F.Paste")
			(net "SAS2X28_B_HDD4_RX_+")
		)
		(pad "A7" smd rect
			(at 5.500116 -0.311404 270)
			(size 0.7112 3.6068)
			(drill
				(offset 0 -0.381)
			)
			(layers "F.Cu" "F.Mask" "F.Paste")
			(net "SAS2X28_B_HDD4_RX_-")
		)
		(pad "A8" smd rect
			(at 4.500118 -0.311404 270)
			(size 0.7112 3.6068)
			(drill
				(offset 0 -0.381)
			)
			(layers "F.Cu" "F.Mask" "F.Paste")
			(net "GND")
		)
		(pad "A9" smd rect
			(at 3.50012 -0.311404 270)
			(size 0.7112 3.6068)
			(drill
				(offset 0 -0.381)
			)
			(layers "F.Cu" "F.Mask" "F.Paste")
			(net "GND")
		)
		(pad "A10" smd rect
			(at 2.500122 -0.311404 270)
			(size 0.7112 3.6068)
			(drill
				(offset 0 -0.381)
			)
			(layers "F.Cu" "F.Mask" "F.Paste")
			(net "SAS2X28_B_HDD9_RX_+")
		)
		(pad "A11" smd rect
			(at 1.500124 -0.311404 270)
			(size 0.7112 3.6068)
			(drill
				(offset 0 -0.381)
			)
			(layers "F.Cu" "F.Mask" "F.Paste")
			(net "SAS2X28_B_HDD9_RX_-")
		)
		(pad "A12" smd rect
			(at -1.500124 -0.311404 270)
			(size 0.7112 3.6068)
			(drill
				(offset 0 -0.381)
			)
			(layers "F.Cu" "F.Mask" "F.Paste")
			(net "TRAY_ID")
		)
		(pad "A13" smd rect
			(at -2.500376 -0.311404 270)
			(size 0.7112 3.6068)
			(drill
				(offset 0 -0.381)
			)
			(layers "F.Cu" "F.Mask" "F.Paste")
			(net "GND")
		)
		(pad "A14" smd rect
			(at -3.500374 -0.311404 270)
			(size 0.7112 3.6068)
			(drill
				(offset 0 -0.381)
			)
			(layers "F.Cu" "F.Mask" "F.Paste")
			(net "SAS2X28_B_HDD3_RX_+")
		)
		(pad "A15" smd rect
			(at -4.500372 -0.311404 270)
			(size 0.7112 3.6068)
			(drill
				(offset 0 -0.381)
			)
			(layers "F.Cu" "F.Mask" "F.Paste")
			(net "SAS2X28_B_HDD3_RX_-")
		)
		(pad "A16" smd rect
			(at -5.50037 -0.311404 270)
			(size 0.7112 3.6068)
			(drill
				(offset 0 -0.381)
			)
			(layers "F.Cu" "F.Mask" "F.Paste")
			(net "GND")
		)
		(pad "A17" smd rect
			(at -6.500368 -0.311404 270)
			(size 0.7112 3.6068)
			(drill
				(offset 0 -0.381)
			)
			(layers "F.Cu" "F.Mask" "F.Paste")
			(net "GND")
		)
		(pad "A18" smd rect
			(at -7.500366 -0.311404 270)
			(size 0.7112 3.6068)
			(drill
				(offset 0 -0.381)
			)
			(layers "F.Cu" "F.Mask" "F.Paste")
			(net "SAS2X28_B_HDD2_RX_+")
		)
		(pad "A19" smd rect
			(at -8.500364 -0.311404 270)
			(size 0.7112 3.6068)
			(drill
				(offset 0 -0.381)
			)
			(layers "F.Cu" "F.Mask" "F.Paste")
			(net "SAS2X28_B_HDD2_RX_-")
		)
		(pad "A20" smd rect
			(at -9.500362 -0.311404 270)
			(size 0.7112 3.6068)
			(drill
				(offset 0 -0.381)
			)
			(layers "F.Cu" "F.Mask" "F.Paste")
			(net "GND")
		)
		(pad "A21" smd rect
			(at -10.50036 -0.311404 270)
			(size 0.7112 3.6068)
			(drill
				(offset 0 -0.381)
			)
			(layers "F.Cu" "F.Mask" "F.Paste")
			(net "GND")
		)
		(pad "A22" smd rect
			(at -11.500358 -0.311404 270)
			(size 0.7112 3.6068)
			(drill
				(offset 0 -0.381)
			)
			(layers "F.Cu" "F.Mask" "F.Paste")
			(net "SAS2X28_B_HDD8_RX_+")
		)
		(pad "A23" smd rect
			(at -12.500356 -0.311404 270)
			(size 0.7112 3.6068)
			(drill
				(offset 0 -0.381)
			)
			(layers "F.Cu" "F.Mask" "F.Paste")
			(net "SAS2X28_B_HDD8_RX_-")
		)
		(pad "A24" smd rect
			(at -13.500354 -0.311404 270)
			(size 0.7112 3.6068)
			(drill
				(offset 0 -0.381)
			)
			(layers "F.Cu" "F.Mask" "F.Paste")
			(net "GND")
		)
		(pad "A25" smd rect
			(at -14.500352 -0.311404 270)
			(size 0.7112 3.6068)
			(drill
				(offset 0 -0.381)
			)
			(layers "F.Cu" "F.Mask" "F.Paste")
			(net "GND")
		)
		(pad "A26" smd rect
			(at -15.50035 -0.311404 270)
			(size 0.7112 3.6068)
			(drill
				(offset 0 -0.381)
			)
			(layers "F.Cu" "F.Mask" "F.Paste")
			(net "SAS2X28_B_HDD7_RX_+")
		)
		(pad "A27" smd rect
			(at -16.500348 -0.311404 270)
			(size 0.7112 3.6068)
			(drill
				(offset 0 -0.381)
			)
			(layers "F.Cu" "F.Mask" "F.Paste")
			(net "SAS2X28_B_HDD7_RX_-")
		)
		(pad "A28" smd rect
			(at -17.500346 -0.311404 270)
			(size 0.7112 3.6068)
			(drill
				(offset 0 -0.381)
			)
			(layers "F.Cu" "F.Mask" "F.Paste")
			(net "GND")
		)
		(pad "A29" smd rect
			(at -18.500344 -0.311404 270)
			(size 0.7112 3.6068)
			(drill
				(offset 0 -0.381)
			)
			(layers "F.Cu" "F.Mask" "F.Paste")
			(net "GND")
		)
		(pad "A30" smd rect
			(at -19.500342 -0.311404 270)
			(size 0.7112 3.6068)
			(drill
				(offset 0 -0.381)
			)
			(layers "F.Cu" "F.Mask" "F.Paste")
			(net "SAS2X28_B_HDD1_RX_+")
		)
		(pad "A31" smd rect
			(at -20.50034 -0.311404 270)
			(size 0.7112 3.6068)
			(drill
				(offset 0 -0.381)
			)
			(layers "F.Cu" "F.Mask" "F.Paste")
			(net "SAS2X28_B_HDD1_RX_-")
		)
		(pad "A32" smd rect
			(at -21.500338 -0.311404 270)
			(size 0.7112 3.6068)
			(drill
				(offset 0 -0.381)
			)
			(layers "F.Cu" "F.Mask" "F.Paste")
			(net "GND")
		)
		(pad "A33" smd rect
			(at -22.500336 -0.311404 270)
			(size 0.7112 3.6068)
			(drill
				(offset 0 -0.381)
			)
			(layers "F.Cu" "F.Mask" "F.Paste")
			(net "GND")
		)
		(pad "A34" smd rect
			(at -23.500334 -0.311404 270)
			(size 0.7112 3.6068)
			(drill
				(offset 0 -0.381)
			)
			(layers "F.Cu" "F.Mask" "F.Paste")
			(net "SAS2X28_B_HDD0_RX_+")
		)
		(pad "A35" smd rect
			(at -24.500332 -0.311404 270)
			(size 0.7112 3.6068)
			(drill
				(offset 0 -0.381)
			)
			(layers "F.Cu" "F.Mask" "F.Paste")
			(net "SAS2X28_B_HDD0_RX_-")
		)
		(pad "A36" smd rect
			(at -25.50033 -0.311404 270)
			(size 0.7112 3.6068)
			(drill
				(offset 0 -0.381)
			)
			(layers "F.Cu" "F.Mask" "F.Paste")
			(net "GND")
		)
		(pad "A37" smd rect
			(at -26.500328 -0.311404 270)
			(size 0.7112 3.6068)
			(drill
				(offset 0 -0.381)
			)
			(layers "F.Cu" "F.Mask" "F.Paste")
			(net "GND")
		)
		(pad "A38" smd rect
			(at -27.500326 -0.311404 270)
			(size 0.7112 3.6068)
			(drill
				(offset 0 -0.381)
			)
			(layers "F.Cu" "F.Mask" "F.Paste")
			(net "SAS2X28_B_HDD13_RX_+")
		)
		(pad "A39" smd rect
			(at -28.500324 -0.311404 270)
			(size 0.7112 3.6068)
			(drill
				(offset 0 -0.381)
			)
			(layers "F.Cu" "F.Mask" "F.Paste")
			(net "SAS2X28_B_HDD13_RX_-")
		)
		(pad "A40" smd rect
			(at -29.500322 -0.311404 270)
			(size 0.7112 3.6068)
			(drill
				(offset 0 -0.381)
			)
			(layers "F.Cu" "F.Mask" "F.Paste")
			(net "GND")
		)
		(pad "A41" smd rect
			(at -30.50032 -0.311404 270)
			(size 0.7112 3.6068)
			(drill
				(offset 0 -0.381)
			)
			(layers "F.Cu" "F.Mask" "F.Paste")
			(net "SD_LATCH_RELEASE")
		)
		(pad "A42" smd rect
			(at -31.500318 -0.311404 270)
			(size 0.7112 3.6068)
			(drill
				(offset 0 -0.381)
			)
			(layers "F.Cu" "F.Mask" "F.Paste")
			(net "SAS2X28_B_HDD4_FLT")
		)
		(pad "A43" smd rect
			(at -32.500316 -0.311404 270)
			(size 0.7112 3.6068)
			(drill
				(offset 0 -0.381)
			)
			(layers "F.Cu" "F.Mask" "F.Paste")
			(net "SAS2X28_B_HDD14_FLT")
		)
		(pad "A44" smd rect
			(at -33.500314 -0.311404 270)
			(size 0.7112 3.6068)
			(drill
				(offset 0 -0.381)
			)
			(layers "F.Cu" "F.Mask" "F.Paste")
			(net "SAS2X28_B_HDD9_FLT")
		)
		(pad "A45" smd rect
			(at -34.500312 -0.311404 270)
			(size 0.7112 3.6068)
			(drill
				(offset 0 -0.381)
			)
			(layers "F.Cu" "F.Mask" "F.Paste")
			(net "SAS2X28_B_HDD3_FLT")
		)
		(pad "A46" smd rect
			(at -35.50031 -0.311404 270)
			(size 0.7112 3.6068)
			(drill
				(offset 0 -0.381)
			)
			(layers "F.Cu" "F.Mask" "F.Paste")
			(net "SAS2X28_B_HDD2_FLT")
		)
		(pad "A47" smd rect
			(at -36.500308 -0.311404 270)
			(size 0.7112 3.6068)
			(drill
				(offset 0 -0.381)
			)
			(layers "F.Cu" "F.Mask" "F.Paste")
			(net "SAS2X28_B_HDD8_FLT")
		)
		(pad "A48" smd rect
			(at -37.500306 -0.311404 270)
			(size 0.7112 3.6068)
			(drill
				(offset 0 -0.381)
			)
			(layers "F.Cu" "F.Mask" "F.Paste")
			(net "SAS2X28_B_HDD7_FLT")
		)
		(pad "A49" smd rect
			(at -38.500304 -0.311404 270)
			(size 0.7112 3.6068)
			(drill
				(offset 0 -0.381)
			)
			(layers "F.Cu" "F.Mask" "F.Paste")
			(net "SAS2X28_B_HDD1_FLT")
		)
		(pad "A50" smd rect
			(at -39.500302 -0.311404 270)
			(size 0.7112 3.6068)
			(drill
				(offset 0 -0.381)
			)
			(layers "F.Cu" "F.Mask" "F.Paste")
			(net "SAS2X28_B_HDD0_FLT")
		)
		(pad "A51" smd rect
			(at -40.5003 -0.311404 270)
			(size 0.7112 3.6068)
			(drill
				(offset 0 -0.381)
			)
			(layers "F.Cu" "F.Mask" "F.Paste")
			(net "GND")
		)
		(pad "A52" smd rect
			(at -41.500298 -0.311404 270)
			(size 0.7112 3.6068)
			(drill
				(offset 0 -0.381)
			)
			(layers "F.Cu" "F.Mask" "F.Paste")
			(net "SAS2X28_B_HDD6_RX_+")
		)
		(pad "A53" smd rect
			(at -42.500296 -0.311404 270)
			(size 0.7112 3.6068)
			(drill
				(offset 0 -0.381)
			)
			(layers "F.Cu" "F.Mask" "F.Paste")
			(net "SAS2X28_B_HDD6_RX_-")
		)
		(pad "A54" smd rect
			(at -43.500294 -0.311404 270)
			(size 0.7112 3.6068)
			(drill
				(offset 0 -0.381)
			)
			(layers "F.Cu" "F.Mask" "F.Paste")
			(net "GND")
		)
		(pad "A55" smd rect
			(at -44.500292 -0.311404 270)
			(size 0.7112 3.6068)
			(drill
				(offset 0 -0.381)
			)
			(layers "F.Cu" "F.Mask" "F.Paste")
			(net "I2C_C_SCL_DAMP_B")
		)
		(pad "A56" smd rect
			(at -45.50029 -0.311404 270)
			(size 0.7112 3.6068)
			(drill
				(offset 0 -0.381)
			)
			(layers "F.Cu" "F.Mask" "F.Paste")
			(net "I2C_C_SDA_DAMP_B")
		)
		(pad "A57" smd rect
			(at -46.500288 -0.311404 270)
			(size 0.7112 3.6068)
			(drill
				(offset 0 -0.381)
			)
			(layers "F.Cu" "F.Mask" "F.Paste")
			(net "I2C_D_SCL_DAMP_B")
		)
		(pad "A58" smd rect
			(at -47.500286 -0.311404 270)
			(size 0.7112 3.6068)
			(drill
				(offset 0 -0.381)
			)
			(layers "F.Cu" "F.Mask" "F.Paste")
			(net "I2C_D_SDA_DAMP_B")
		)
		(pad "A59" smd rect
			(at -48.500284 -0.311404 270)
			(size 0.7112 3.6068)
			(drill
				(offset 0 -0.381)
			)
			(layers "F.Cu" "F.Mask" "F.Paste")
			(net "GND")
		)
		(pad "A60" smd rect
			(at -49.500282 -0.311404 270)
			(size 0.7112 3.6068)
			(drill
				(offset 0 -0.381)
			)
			(layers "F.Cu" "F.Mask" "F.Paste")
			(net "SAS2X28_B_HDD5_RX_+")
		)
		(pad "A61" smd rect
			(at -50.50028 -0.311404 270)
			(size 0.7112 3.6068)
			(drill
				(offset 0 -0.381)
			)
			(layers "F.Cu" "F.Mask" "F.Paste")
			(net "SAS2X28_B_HDD5_RX_-")
		)
		(pad "A62" smd rect
			(at -51.500278 -0.311404 270)
			(size 0.7112 3.6068)
			(drill
				(offset 0 -0.381)
			)
			(layers "F.Cu" "F.Mask" "F.Paste")
			(net "GND")
		)
		(pad "A63" smd rect
			(at -52.500276 -0.311404 270)
			(size 0.7112 3.6068)
			(drill
				(offset 0 -0.381)
			)
			(layers "F.Cu" "F.Mask" "F.Paste")
			(net "GND")
		)
		(pad "A64" smd rect
			(at -53.500274 -0.311404 270)
			(size 0.7112 3.6068)
			(drill
				(offset 0 -0.381)
			)
			(layers "F.Cu" "F.Mask" "F.Paste")
			(net "SAS2X28_B_HDD10_RX_+")
		)
		(pad "A65" smd rect
			(at -54.500272 -0.311404 270)
			(size 0.7112 3.6068)
			(drill
				(offset 0 -0.381)
			)
			(layers "F.Cu" "F.Mask" "F.Paste")
			(net "SAS2X28_B_HDD10_RX_-")
		)
		(pad "A66" smd rect
			(at -55.50027 -0.311404 270)
			(size 0.7112 3.6068)
			(drill
				(offset 0 -0.381)
			)
			(layers "F.Cu" "F.Mask" "F.Paste")
			(net "GND")
		)
		(pad "A67" smd rect
			(at -56.500268 -0.311404 270)
			(size 0.7112 3.6068)
			(drill
				(offset 0 -0.381)
			)
			(layers "F.Cu" "F.Mask" "F.Paste")
			(net "GND")
		)
		(pad "A68" smd rect
			(at -57.500266 -0.311404 270)
			(size 0.7112 3.6068)
			(drill
				(offset 0 -0.381)
			)
			(layers "F.Cu" "F.Mask" "F.Paste")
			(net "SAS2X28_B_HDD11_RX_+")
		)
		(pad "A69" smd rect
			(at -58.500264 -0.311404 270)
			(size 0.7112 3.6068)
			(drill
				(offset 0 -0.381)
			)
			(layers "F.Cu" "F.Mask" "F.Paste")
			(net "SAS2X28_B_HDD11_RX_-")
		)
		(pad "A70" smd rect
			(at -59.500262 -0.311404 270)
			(size 0.7112 3.6068)
			(drill
				(offset 0 -0.381)
			)
			(layers "F.Cu" "F.Mask" "F.Paste")
			(net "GND")
		)
		(pad "A71" smd rect
			(at -60.50026 -0.311404 270)
			(size 0.7112 3.6068)
			(drill
				(offset 0 -0.381)
			)
			(layers "F.Cu" "F.Mask" "F.Paste")
			(net "GND")
		)
		(pad "A72" smd rect
			(at -61.500258 -0.311404 270)
			(size 0.7112 3.6068)
			(drill
				(offset 0 -0.381)
			)
			(layers "F.Cu" "F.Mask" "F.Paste")
			(net "SAS2X28_B_HDD12_RX_+")
		)
		(pad "A73" smd rect
			(at -62.500256 -0.311404 270)
			(size 0.7112 3.6068)
			(drill
				(offset 0 -0.381)
			)
			(layers "F.Cu" "F.Mask" "F.Paste")
			(net "SAS2X28_B_HDD12_RX_-")
		)
		(pad "A74" smd rect
			(at -63.500254 -0.311404 270)
			(size 0.7112 3.6068)
			(drill
				(offset 0 -0.381)
			)
			(layers "F.Cu" "F.Mask" "F.Paste")
			(net "GND")
		)
		(pad "A75" smd rect
			(at -64.500252 -0.311404 270)
			(size 0.7112 3.6068)
			(drill
				(offset 0 -0.381)
			)
			(layers "F.Cu" "F.Mask" "F.Paste")
			(net "GND")
		)
		(pad "A76" smd rect
			(at -65.50025 -0.311404 270)
			(size 0.7112 3.6068)
			(drill
				(offset 0 -0.381)
			)
			(layers "F.Cu" "F.Mask" "F.Paste")
			(net "SEB_AB_RX+")
		)
		(pad "A77" smd rect
			(at -66.500248 -0.311404 270)
			(size 0.7112 3.6068)
			(drill
				(offset 0 -0.381)
			)
			(layers "F.Cu" "F.Mask" "F.Paste")
			(net "SEB_AB_RX-")
		)
		(pad "A78" smd rect
			(at -67.500246 -0.311404 270)
			(size 0.7112 3.6068)
			(drill
				(offset 0 -0.381)
			)
			(layers "F.Cu" "F.Mask" "F.Paste")
			(net "GND")
		)
		(pad "A79" smd rect
			(at -68.500244 -0.311404 270)
			(size 0.7112 3.6068)
			(drill
				(offset 0 -0.381)
			)
			(layers "F.Cu" "F.Mask" "F.Paste")
			(net "PEER_1B&2B_HB")
		)
		(pad "A80" smd rect
			(at -69.500242 -0.311404 270)
			(size 0.7112 3.6068)
			(drill
				(offset 0 -0.381)
			)
			(layers "F.Cu" "F.Mask" "F.Paste")
			(net "P12V")
		)
		(pad "A81" smd rect
			(at -70.50024 -0.311404 270)
			(size 0.7112 3.6068)
			(drill
				(offset 0 -0.381)
			)
			(layers "F.Cu" "F.Mask" "F.Paste")
			(net "P12V")
		)
		(pad "A82" smd rect
			(at -71.500238 -0.311404 270)
			(size 0.7112 3.6068)
			(drill
				(offset 0 -0.381)
			)
			(layers "F.Cu" "F.Mask" "F.Paste")
			(net "P12V")
		)
		(pad "B1" smd rect
			(at 11.500104 -0.692404 270)
			(size 0.7112 3.6068)
			(layers "F.Cu" "F.Mask" "F.Paste")
			(net "SAS2X28_B_PRSNT15")
		)
		(pad "B2" smd rect
			(at 10.500106 -0.692404 270)
			(size 0.7112 3.6068)
			(layers "F.Cu" "F.Mask" "F.Paste")
			(net "FCB_HW_REV")
		)
		(pad "B3" smd rect
			(at 9.500108 -0.692404 270)
			(size 0.7112 3.6068)
			(layers "F.Cu" "F.Mask" "F.Paste")
			(net "GND")
		)
		(pad "B4" smd rect
			(at 8.50011 -0.692404 270)
			(size 0.7112 3.6068)
			(layers "F.Cu" "F.Mask" "F.Paste")
			(net "SAS2X28_B_HDD14_TX_+")
		)
		(pad "B5" smd rect
			(at 7.500112 -0.692404 270)
			(size 0.7112 3.6068)
			(layers "F.Cu" "F.Mask" "F.Paste")
			(net "SAS2X28_B_HDD14_TX_-")
		)
		(pad "B6" smd rect
			(at 6.500114 -0.692404 270)
			(size 0.7112 3.6068)
			(layers "F.Cu" "F.Mask" "F.Paste")
			(net "GND")
		)
		(pad "B7" smd rect
			(at 5.500116 -0.692404 270)
			(size 0.7112 3.6068)
			(layers "F.Cu" "F.Mask" "F.Paste")
			(net "GND")
		)
		(pad "B8" smd rect
			(at 4.500118 -0.692404 270)
			(size 0.7112 3.6068)
			(layers "F.Cu" "F.Mask" "F.Paste")
			(net "SAS2X28_B_HDD4_TX_+")
		)
		(pad "B9" smd rect
			(at 3.50012 -0.692404 270)
			(size 0.7112 3.6068)
			(layers "F.Cu" "F.Mask" "F.Paste")
			(net "SAS2X28_B_HDD4_TX_-")
		)
	)
)
